(kicad_pcb
	(version 20260206)
	(generator "pcbnew")
	(generator_version "10.0")
	(general
		(thickness 1.6)
		(legacy_teardrops no)
	)
	(paper "A4")
	(title_block
		(title "03242023_DA0F0TMBIJ0_F0T_Motherboard_J_brd_V01_OCP.brd")
		(comment 1 "Grand Teton / footprints 5590-5595 of 6105")
	)
	(layers
		(0 "F.Cu" signal "TOP")
		(4 "In1.Cu" signal "GND")
		(6 "In2.Cu" signal "IN1")
		(8 "In3.Cu" signal "GND1")
		(10 "In4.Cu" signal "IN2")
		(12 "In5.Cu" signal "GND2")
		(14 "In6.Cu" signal "IN3")
		(16 "In7.Cu" signal "GND3")
		(18 "In8.Cu" signal "VCC")
		(20 "In9.Cu" signal "VCC1")
		(22 "In10.Cu" signal "GND4")
		(24 "In11.Cu" signal "IN4")
		(26 "In12.Cu" signal "GND5")
		(28 "In13.Cu" signal "IN5")
		(30 "In14.Cu" signal "GND6")
		(32 "In15.Cu" signal "IN6")
		(34 "In16.Cu" signal "GND7")
		(2 "B.Cu" signal "BOTTOM")
		(9 "F.Adhes" user "F.Adhesive")
		(11 "B.Adhes" user "B.Adhesive")
		(13 "F.Paste" user "Package Geometry/Pastemask Top")
		(15 "B.Paste" user "Package Geometry/Pastemask Bottom")
		(5 "F.SilkS" user "Ref Des/Silkscreen Top")
		(7 "B.SilkS" user "Ref Des/Silkscreen Bottom")
		(1 "F.Mask" user "Board Geometry/Soldermask Top")
		(3 "B.Mask" user "Board Geometry/Soldermask Bottom")
		(17 "Dwgs.User" user "User.Drawings")
		(19 "Cmts.User" user "User.Comments")
		(21 "Eco1.User" user "User.Eco1")
		(23 "Eco2.User" user "User.Eco2")
		(25 "Edge.Cuts" user "Board Geometry/Outline")
		(27 "Margin" user)
		(31 "F.CrtYd" user "Package Geometry/Place Bound Top")
		(29 "B.CrtYd" user "Package Geometry/Place Bound Bottom")
		(35 "F.Fab" user "Ref Des/Assembly Top")
		(33 "B.Fab" user "Ref Des/Assembly Bottom")
	)
	(footprint ""
		(layer "B.Cu")
		(at 430.600104 -135.510778)
		(property "Reference" "R2393"
			(at 0 0 0)
			(layer "B.SilkS")
			(hide yes)
			(effects
				(font
					(size 1.27 1.27)
				)
				(justify mirror)
			)
		)
		(property "Value" ""
			(at 0 0 0)
			(layer "B.Fab")
			(effects
				(font
					(size 1.27 1.27)
				)
				(justify mirror)
			)
		)
		(duplicate_pad_numbers_are_jumpers no)
		(fp_line
			(start -0.7874 -0.4064)
			(end -0.7874 0.4064)
			(stroke
				(width 0.1524)
				(type default)
			)
			(layer "B.SilkS")
		)
		(fp_line
			(start -0.7874 0.4064)
			(end 0.7874 0.4064)
			(stroke
				(width 0.1524)
				(type default)
			)
			(layer "B.SilkS")
		)
		(fp_line
			(start 0.7874 -0.4064)
			(end -0.7874 -0.4064)
			(stroke
				(width 0.1524)
				(type default)
			)
			(layer "B.SilkS")
		)
		(fp_line
			(start 0.7874 0.4064)
			(end 0.7874 -0.4064)
			(stroke
				(width 0.1524)
				(type default)
			)
			(layer "B.SilkS")
		)
		(fp_line
			(start -0.67945 -0.3048)
			(end -0.67945 0.3048)
			(stroke
				(width 0.1)
				(type default)
			)
			(layer "B.Fab")
		)
		(fp_line
			(start -0.67945 0.3048)
			(end -0.120396 0.3048)
			(stroke
				(width 0.1)
				(type default)
			)
			(layer "B.Fab")
		)
		(fp_line
			(start -0.12065 -0.3048)
			(end -0.67945 -0.3048)
			(stroke
				(width 0.1)
				(type default)
			)
			(layer "B.Fab")
		)
		(fp_line
			(start -0.12065 -0.2794)
			(end -0.12065 -0.3048)
			(stroke
				(width 0.1)
				(type default)
			)
			(layer "B.Fab")
		)
		(fp_line
			(start -0.120396 0.2794)
			(end 0.12065 0.2794)
			(stroke
				(width 0.1)
				(type default)
			)
			(layer "B.Fab")
		)
		(fp_line
			(start -0.120396 0.3048)
			(end -0.120396 0.2794)
			(stroke
				(width 0.1)
				(type default)
			)
			(layer "B.Fab")
		)
		(fp_line
			(start 0.12065 -0.305054)
			(end 0.12065 -0.2794)
			(stroke
				(width 0.1)
				(type default)
			)
			(layer "B.Fab")
		)
		(fp_line
			(start 0.12065 -0.2794)
			(end -0.12065 -0.2794)
			(stroke
				(width 0.1)
				(type default)
			)
			(layer "B.Fab")
		)
		(fp_line
			(start 0.12065 0.2794)
			(end 0.12065 0.3048)
			(stroke
				(width 0.1)
				(type default)
			)
			(layer "B.Fab")
		)
		(fp_line
			(start 0.12065 0.3048)
			(end 0.67945 0.3048)
			(stroke
				(width 0.1)
				(type default)
			)
			(layer "B.Fab")
		)
		(fp_line
			(start 0.67945 -0.305054)
			(end 0.12065 -0.305054)
			(stroke
				(width 0.1)
				(type default)
			)
			(layer "B.Fab")
		)
		(fp_line
			(start 0.67945 0.3048)
			(end 0.67945 -0.305054)
			(stroke
				(width 0.1)
				(type default)
			)
			(layer "B.Fab")
		)
		(pad "1" smd circle
			(at 0.40005 0 180)
			(size 0 0)
			(layers "B.Cu" "B.Mask" "B.Paste")
			(net "P3V3_AUX")
		)
		(pad "2" smd circle
			(at -0.40005 0 180)
			(size 0 0)
			(layers "B.Cu" "B.Mask" "B.Paste")
			(net "PVCCINFAON_CPU0_PIN_ALERT")
		)
	)
	(footprint ""
		(layer "B.Cu")
		(at 280.852118 -319.120774 -90)
		(property "Reference" "R31"
			(at 0 0 90)
			(layer "B.SilkS")
			(hide yes)
			(effects
				(font
					(size 1.27 1.27)
				)
				(justify mirror)
			)
		)
		(property "Value" ""
			(at 0 0 90)
			(layer "B.Fab")
			(effects
				(font
					(size 1.27 1.27)
				)
				(justify mirror)
			)
		)
		(duplicate_pad_numbers_are_jumpers no)
		(fp_line
			(start -0.7874 0.4064)
			(end 0.7874 0.4064)
			(stroke
				(width 0.1524)
				(type default)
			)
			(layer "B.SilkS")
		)
		(fp_line
			(start 0.7874 0.4064)
			(end 0.7874 -0.4064)
			(stroke
				(width 0.1524)
				(type default)
			)
			(layer "B.SilkS")
		)
		(fp_line
			(start -0.7874 -0.4064)
			(end -0.7874 0.4064)
			(stroke
				(width 0.1524)
				(type default)
			)
			(layer "B.SilkS")
		)
		(fp_line
			(start 0.7874 -0.4064)
			(end -0.7874 -0.4064)
			(stroke
				(width 0.1524)
				(type default)
			)
			(layer "B.SilkS")
		)
		(fp_line
			(start -0.67945 0.3048)
			(end -0.120396 0.3048)
			(stroke
				(width 0.1)
				(type default)
			)
			(layer "B.Fab")
		)
		(fp_line
			(start -0.120396 0.3048)
			(end -0.120396 0.2794)
			(stroke
				(width 0.1)
				(type default)
			)
			(layer "B.Fab")
		)
		(fp_line
			(start 0.12065 0.3048)
			(end 0.67945 0.3048)
			(stroke
				(width 0.1)
				(type default)
			)
			(layer "B.Fab")
		)
		(fp_line
			(start 0.67945 0.3048)
			(end 0.67945 -0.305054)
			(stroke
				(width 0.1)
				(type default)
			)
			(layer "B.Fab")
		)
		(fp_line
			(start -0.120396 0.2794)
			(end 0.12065 0.2794)
			(stroke
				(width 0.1)
				(type default)
			)
			(layer "B.Fab")
		)
		(fp_line
			(start 0.12065 0.2794)
			(end 0.12065 0.3048)
			(stroke
				(width 0.1)
				(type default)
			)
			(layer "B.Fab")
		)
		(fp_line
			(start -0.12065 -0.2794)
			(end -0.12065 -0.3048)
			(stroke
				(width 0.1)
				(type default)
			)
			(layer "B.Fab")
		)
		(fp_line
			(start 0.12065 -0.2794)
			(end -0.12065 -0.2794)
			(stroke
				(width 0.1)
				(type default)
			)
			(layer "B.Fab")
		)
		(fp_line
			(start -0.67945 -0.3048)
			(end -0.67945 0.3048)
			(stroke
				(width 0.1)
				(type default)
			)
			(layer "B.Fab")
		)
		(fp_line
			(start -0.12065 -0.3048)
			(end -0.67945 -0.3048)
			(stroke
				(width 0.1)
				(type default)
			)
			(layer "B.Fab")
		)
		(fp_line
			(start 0.12065 -0.305054)
			(end 0.12065 -0.2794)
			(stroke
				(width 0.1)
				(type default)
			)
			(layer "B.Fab")
		)
		(fp_line
			(start 0.67945 -0.305054)
			(end 0.12065 -0.305054)
			(stroke
				(width 0.1)
				(type default)
			)
			(layer "B.Fab")
		)
		(pad "1" smd circle
			(at 0.40005 0 90)
			(size 0 0)
			(layers "B.Cu" "B.Mask" "B.Paste")
			(net "PD_CHC_CPU0_DIMM2_SAA")
		)
		(pad "2" smd circle
			(at -0.40005 0 90)
			(size 0 0)
			(layers "B.Cu" "B.Mask" "B.Paste")
			(net "GND")
		)
	)
	(footprint ""
		(layer "B.Cu")
		(at 304.138584 -151.719534 -90)
		(property "Reference" "R685"
			(at 0 0 90)
			(layer "B.SilkS")
			(hide yes)
			(effects
				(font
					(size 1.27 1.27)
				)
				(justify mirror)
			)
		)
		(property "Value" ""
			(at 0 0 90)
			(layer "B.Fab")
			(effects
				(font
					(size 1.27 1.27)
				)
				(justify mirror)
			)
		)
		(duplicate_pad_numbers_are_jumpers no)
		(fp_line
			(start -0.7874 0.4064)
			(end 0.7874 0.4064)
			(stroke
				(width 0.1524)
				(type default)
			)
			(layer "B.SilkS")
		)
		(fp_line
			(start 0.7874 0.4064)
			(end 0.7874 -0.4064)
			(stroke
				(width 0.1524)
				(type default)
			)
			(layer "B.SilkS")
		)
		(fp_line
			(start -0.7874 -0.4064)
			(end -0.7874 0.4064)
			(stroke
				(width 0.1524)
				(type default)
			)
			(layer "B.SilkS")
		)
		(fp_line
			(start 0.7874 -0.4064)
			(end -0.7874 -0.4064)
			(stroke
				(width 0.1524)
				(type default)
			)
			(layer "B.SilkS")
		)
		(fp_line
			(start -0.67945 0.3048)
			(end -0.120396 0.3048)
			(stroke
				(width 0.1)
				(type default)
			)
			(layer "B.Fab")
		)
		(fp_line
			(start -0.120396 0.3048)
			(end -0.120396 0.2794)
			(stroke
				(width 0.1)
				(type default)
			)
			(layer "B.Fab")
		)
		(fp_line
			(start 0.12065 0.3048)
			(end 0.67945 0.3048)
			(stroke
				(width 0.1)
				(type default)
			)
			(layer "B.Fab")
		)
		(fp_line
			(start 0.67945 0.3048)
			(end 0.67945 -0.305054)
			(stroke
				(width 0.1)
				(type default)
			)
			(layer "B.Fab")
		)
		(fp_line
			(start -0.120396 0.2794)
			(end 0.12065 0.2794)
			(stroke
				(width 0.1)
				(type default)
			)
			(layer "B.Fab")
		)
		(fp_line
			(start 0.12065 0.2794)
			(end 0.12065 0.3048)
			(stroke
				(width 0.1)
				(type default)
			)
			(layer "B.Fab")
		)
		(fp_line
			(start -0.12065 -0.2794)
			(end -0.12065 -0.3048)
			(stroke
				(width 0.1)
				(type default)
			)
			(layer "B.Fab")
		)
		(fp_line
			(start 0.12065 -0.2794)
			(end -0.12065 -0.2794)
			(stroke
				(width 0.1)
				(type default)
			)
			(layer "B.Fab")
		)
		(fp_line
			(start -0.67945 -0.3048)
			(end -0.67945 0.3048)
			(stroke
				(width 0.1)
				(type default)
			)
			(layer "B.Fab")
		)
		(fp_line
			(start -0.12065 -0.3048)
			(end -0.67945 -0.3048)
			(stroke
				(width 0.1)
				(type default)
			)
			(layer "B.Fab")
		)
		(fp_line
			(start 0.12065 -0.305054)
			(end 0.12065 -0.2794)
			(stroke
				(width 0.1)
				(type default)
			)
			(layer "B.Fab")
		)
		(fp_line
			(start 0.67945 -0.305054)
			(end 0.12065 -0.305054)
			(stroke
				(width 0.1)
				(type default)
			)
			(layer "B.Fab")
		)
		(pad "1" smd circle
			(at 0.40005 0 90)
			(size 0 0)
			(layers "B.Cu" "B.Mask" "B.Paste")
			(net "I3C_SPD_DDREFGH_CPU0_R_SDA")
		)
		(pad "2" smd circle
			(at -0.40005 0 90)
			(size 0 0)
			(layers "B.Cu" "B.Mask" "B.Paste")
			(net "I3C_SPD_DDREFGH_CPU0_LVC1_R_SDA")
		)
	)
	(footprint ""
		(layer "B.Cu")
		(at 188.46546 -104.823768)
		(property "Reference" "R1416"
			(at 0 0 0)
			(layer "B.SilkS")
			(hide yes)
			(effects
				(font
					(size 1.27 1.27)
				)
				(justify mirror)
			)
		)
		(property "Value" ""
			(at 0 0 0)
			(layer "B.Fab")
			(effects
				(font
					(size 1.27 1.27)
				)
				(justify mirror)
			)
		)
		(duplicate_pad_numbers_are_jumpers no)
		(fp_line
			(start -0.7874 -0.4064)
			(end -0.7874 0.4064)
			(stroke
				(width 0.1524)
				(type default)
			)
			(layer "B.SilkS")
		)
		(fp_line
			(start -0.7874 0.4064)
			(end 0.7874 0.4064)
			(stroke
				(width 0.1524)
				(type default)
			)
			(layer "B.SilkS")
		)
		(fp_line
			(start 0.7874 -0.4064)
			(end -0.7874 -0.4064)
			(stroke
				(width 0.1524)
				(type default)
			)
			(layer "B.SilkS")
		)
		(fp_line
			(start 0.7874 0.4064)
			(end 0.7874 -0.4064)
			(stroke
				(width 0.1524)
				(type default)
			)
			(layer "B.SilkS")
		)
		(fp_line
			(start -0.67945 -0.3048)
			(end -0.67945 0.3048)
			(stroke
				(width 0.1)
				(type default)
			)
			(layer "B.Fab")
		)
		(fp_line
			(start -0.67945 0.3048)
			(end -0.120396 0.3048)
			(stroke
				(width 0.1)
				(type default)
			)
			(layer "B.Fab")
		)
		(fp_line
			(start -0.12065 -0.3048)
			(end -0.67945 -0.3048)
			(stroke
				(width 0.1)
				(type default)
			)
			(layer "B.Fab")
		)
		(fp_line
			(start -0.12065 -0.2794)
			(end -0.12065 -0.3048)
			(stroke
				(width 0.1)
				(type default)
			)
			(layer "B.Fab")
		)
		(fp_line
			(start -0.120396 0.2794)
			(end 0.12065 0.2794)
			(stroke
				(width 0.1)
				(type default)
			)
			(layer "B.Fab")
		)
		(fp_line
			(start -0.120396 0.3048)
			(end -0.120396 0.2794)
			(stroke
				(width 0.1)
				(type default)
			)
			(layer "B.Fab")
		)
		(fp_line
			(start 0.12065 -0.305054)
			(end 0.12065 -0.2794)
			(stroke
				(width 0.1)
				(type default)
			)
			(layer "B.Fab")
		)
		(fp_line
			(start 0.12065 -0.2794)
			(end -0.12065 -0.2794)
			(stroke
				(width 0.1)
				(type default)
			)
			(layer "B.Fab")
		)
		(fp_line
			(start 0.12065 0.2794)
			(end 0.12065 0.3048)
			(stroke
				(width 0.1)
				(type default)
			)
			(layer "B.Fab")
		)
		(fp_line
			(start 0.12065 0.3048)
			(end 0.67945 0.3048)
			(stroke
				(width 0.1)
				(type default)
			)
			(layer "B.Fab")
		)
		(fp_line
			(start 0.67945 -0.305054)
			(end 0.12065 -0.305054)
			(stroke
				(width 0.1)
				(type default)
			)
			(layer "B.Fab")
		)
		(fp_line
			(start 0.67945 0.3048)
			(end 0.67945 -0.305054)
			(stroke
				(width 0.1)
				(type default)
			)
			(layer "B.Fab")
		)
		(pad "1" smd circle
			(at 0.40005 0 180)
			(size 0 0)
			(layers "B.Cu" "B.Mask" "B.Paste")
			(net "RST_CPU1_LVC1_R_N")
		)
		(pad "2" smd circle
			(at -0.40005 0 180)
			(size 0 0)
			(layers "B.Cu" "B.Mask" "B.Paste")
			(net "GND")
		)
	)
	(footprint ""
		(layer "B.Cu")
		(at 388.989824 -342.936576 90)
		(property "Reference" "PC238_P0_8"
			(at 0 0 90)
			(layer "B.SilkS")
			(hide yes)
			(effects
				(font
					(size 1.27 1.27)
				)
				(justify mirror)
			)
		)
		(property "Value" ""
			(at 0 0 90)
			(layer "B.Fab")
			(effects
				(font
					(size 1.27 1.27)
				)
				(justify mirror)
			)
		)
		(duplicate_pad_numbers_are_jumpers no)
		(fp_line
			(start 1.524 -0.762)
			(end -1.524 -0.762)
			(stroke
				(width 0.1524)
				(type default)
			)
			(layer "B.SilkS")
		)
		(fp_line
			(start -1.524 -0.762)
			(end -1.524 0.762)
			(stroke
				(width 0.1524)
				(type default)
			)
			(layer "B.SilkS")
		)
		(fp_line
			(start 1.524 0.762)
			(end 1.524 -0.762)
			(stroke
				(width 0.1524)
				(type default)
			)
			(layer "B.SilkS")
		)
		(fp_line
			(start -1.524 0.762)
			(end 1.524 0.762)
			(stroke
				(width 0.1524)
				(type default)
			)
			(layer "B.SilkS")
		)
		(fp_line
			(start 1.1049 -0.724916)
			(end 1.1049 0.724916)
			(stroke
				(width 0.1)
				(type default)
			)
			(layer "B.Fab")
		)
		(fp_line
			(start -1.1049 -0.724916)
			(end 1.1049 -0.724916)
			(stroke
				(width 0.1)
				(type default)
			)
			(layer "B.Fab")
		)
		(fp_line
			(start 1.1049 0.724916)
			(end -1.1049 0.724916)
			(stroke
				(width 0.1)
				(type default)
			)
			(layer "B.Fab")
		)
		(fp_line
			(start -1.1049 0.724916)
			(end -1.1049 -0.724916)
			(stroke
				(width 0.1)
				(type default)
			)
			(layer "B.Fab")
		)
		(pad "1" smd rect
			(at 0.889 0 90)
			(size 1.016 1.27)
			(layers "B.Cu" "B.Mask" "B.Paste")
			(net "SW_P12V_PVCCIN_CPU0_FLT")
		)
		(pad "2" smd rect
			(at -0.889 0 90)
			(size 1.016 1.27)
			(layers "B.Cu" "B.Mask" "B.Paste")
			(net "GND")
		)
	)
	(footprint ""
		(layer "B.Cu")
		(at 245.96217 -128.330452 90)
		(property "Reference" "R569"
			(at 0 0 90)
			(layer "B.SilkS")
			(hide yes)
			(effects
				(font
					(size 1.27 1.27)
				)
				(justify mirror)
			)
		)
		(property "Value" ""
			(at 0 0 90)
			(layer "B.Fab")
			(effects
				(font
					(size 1.27 1.27)
				)
				(justify mirror)
			)
		)
		(duplicate_pad_numbers_are_jumpers no)
		(fp_line
			(start 0.7874 -0.4064)
			(end -0.7874 -0.4064)
			(stroke
				(width 0.1524)
				(type default)
			)
			(layer "B.SilkS")
		)
		(fp_line
			(start -0.7874 -0.4064)
			(end -0.7874 0.4064)
			(stroke
				(width 0.1524)
				(type default)
			)
			(layer "B.SilkS")
		)
		(fp_line
			(start 0.7874 0.4064)
			(end 0.7874 -0.4064)
			(stroke
				(width 0.1524)
				(type default)
			)
			(layer "B.SilkS")
		)
		(fp_line
			(start -0.7874 0.4064)
			(end 0.7874 0.4064)
			(stroke
				(width 0.1524)
				(type default)
			)
			(layer "B.SilkS")
		)
		(fp_line
			(start 0.67945 -0.305054)
			(end 0.12065 -0.305054)
			(stroke
				(width 0.1)
				(type default)
			)
			(layer "B.Fab")
		)
		(fp_line
			(start 0.12065 -0.305054)
			(end 0.12065 -0.2794)
			(stroke
				(width 0.1)
				(type default)
			)
			(layer "B.Fab")
		)
		(fp_line
			(start -0.12065 -0.3048)
			(end -0.67945 -0.3048)
			(stroke
				(width 0.1)
				(type default)
			)
			(layer "B.Fab")
		)
		(fp_line
			(start -0.67945 -0.3048)
			(end -0.67945 0.3048)
			(stroke
				(width 0.1)
				(type default)
			)
			(layer "B.Fab")
		)
		(fp_line
			(start 0.12065 -0.2794)
			(end -0.12065 -0.2794)
			(stroke
				(width 0.1)
				(type default)
			)
			(layer "B.Fab")
		)
		(fp_line
			(start -0.12065 -0.2794)
			(end -0.12065 -0.3048)
			(stroke
				(width 0.1)
				(type default)
			)
			(layer "B.Fab")
		)
		(fp_line
			(start 0.12065 0.2794)
			(end 0.12065 0.3048)
			(stroke
				(width 0.1)
				(type default)
			)
			(layer "B.Fab")
		)
		(fp_line
			(start -0.120396 0.2794)
			(end 0.12065 0.2794)
			(stroke
				(width 0.1)
				(type default)
			)
			(layer "B.Fab")
		)
		(fp_line
			(start 0.67945 0.3048)
			(end 0.67945 -0.305054)
			(stroke
				(width 0.1)
				(type default)
			)
			(layer "B.Fab")
		)
		(fp_line
			(start 0.12065 0.3048)
			(end 0.67945 0.3048)
			(stroke
				(width 0.1)
				(type default)
			)
			(layer "B.Fab")
		)
		(fp_line
			(start -0.120396 0.3048)
			(end -0.120396 0.2794)
			(stroke
				(width 0.1)
				(type default)
			)
			(layer "B.Fab")
		)
		(fp_line
			(start -0.67945 0.3048)
			(end -0.120396 0.3048)
			(stroke
				(width 0.1)
				(type default)
			)
			(layer "B.Fab")
		)
		(pad "1" smd circle
			(at 0.40005 0 270)
			(size 0 0)
			(layers "B.Cu" "B.Mask" "B.Paste")
			(net "P3V3")
		)
		(pad "2" smd circle
			(at -0.40005 0 270)
			(size 0 0)
			(layers "B.Cu" "B.Mask" "B.Paste")
			(net "PD_DB2000_SMB_SA0")
		)
	)
)
